# T6G (Grand Teton) — schematic netlist excerpt (pin names and nets, part order shuffled) for the footprints in the layout excerpt that follows; sources: Cadence DE-HDL packaged netlist, KiCad conversion of 04192023_DAF0TMB3IC0_F0TG_MB_C_brd_V02_OCP.brd

R1708  Q_RES  10 1% CHIP  pkg 0402LF  page 106 : A = I3C_SPD_DDRGL_CPU1_SDA ; B = I3C_SPD_DDRI_CPU1_SDA
PC431_5  Q_CAP  22UF 4V 20% X6S  pkg C0805  page 220 : A = PVDDCR_CPU1_P1 ; B = GND
C2473  Q_CAP  22UF 4V 20% X6S  pkg C0402  page 74 : A = PVDDCR_SOC_P1 ; B = GND

(kicad_pcb
	(version 20260206)
	(generator "pcbnew")
	(generator_version "10.0")
	(general
		(thickness 1.6)
		(legacy_teardrops no)
	)
	(paper "A4")
	(title_block
		(title "04192023_DAF0TMB3IC0_F0TG_MB_C_brd_V02_OCP.brd")
		(comment 1 "Grand Teton / footprints 8176-8178 of 8354")
	)
	(layers
		(0 "F.Cu" signal "TOP")
		(4 "In1.Cu" signal "GND")
		(6 "In2.Cu" signal "IN1")
		(8 "In3.Cu" signal "GND1")
		(10 "In4.Cu" signal "IN2")
		(12 "In5.Cu" signal "GND2")
		(14 "In6.Cu" signal "IN3")
		(16 "In7.Cu" signal "GND3")
		(18 "In8.Cu" signal "VCC")
		(20 "In9.Cu" signal "VCC1")
		(22 "In10.Cu" signal "GND4")
		(24 "In11.Cu" signal "IN4")
		(26 "In12.Cu" signal "GND5")
		(28 "In13.Cu" signal "IN5")
		(30 "In14.Cu" signal "GND6")
		(32 "In15.Cu" signal "IN6")
		(34 "In16.Cu" signal "GND7")
		(2 "B.Cu" signal "BOTTOM")
		(9 "F.Adhes" user "F.Adhesive")
		(11 "B.Adhes" user "B.Adhesive")
		(13 "F.Paste" user "Package Geometry/Pastemask Top")
		(15 "B.Paste" user "Package Geometry/Pastemask Bottom")
		(5 "F.SilkS" user "Ref Des/Silkscreen Top")
		(7 "B.SilkS" user "Ref Des/Silkscreen Bottom")
		(1 "F.Mask" user "Board Geometry/Soldermask Top")
		(3 "B.Mask" user "Board Geometry/Soldermask Bottom")
		(17 "Dwgs.User" user "User.Drawings")
		(19 "Cmts.User" user "User.Comments")
		(21 "Eco1.User" user "User.Eco1")
		(23 "Eco2.User" user "User.Eco2")
		(25 "Edge.Cuts" user "Board Geometry/Outline")
		(27 "Margin" user)
		(31 "F.CrtYd" user "Package Geometry/Place Bound Top")
		(29 "B.CrtYd" user "Package Geometry/Place Bound Bottom")
		(35 "F.Fab" user "Ref Des/Assembly Top")
		(33 "B.Fab" user "Ref Des/Assembly Bottom")
	)
	(footprint ""
		(layer "B.Cu")
		(at 111.476028 -256.012442 -90)
		(property "Reference" "C2473"
			(at 0 0 90)
			(layer "B.SilkS")
			(hide yes)
			(effects
				(font
					(size 1.27 1.27)
				)
				(justify mirror)
			)
		)
		(property "Value" ""
			(at 0 0 90)
			(layer "B.Fab")
			(effects
				(font
					(size 1.27 1.27)
				)
				(justify mirror)
			)
		)
		(duplicate_pad_numbers_are_jumpers no)
		(fp_line
			(start -0.7874 0.4064)
			(end 0.7874 0.4064)
			(stroke
				(width 0.1524)
				(type default)
			)
			(layer "B.SilkS")
		)
		(fp_line
			(start 0.7874 0.4064)
			(end 0.7874 -0.4064)
			(stroke
				(width 0.1524)
				(type default)
			)
			(layer "B.SilkS")
		)
		(fp_line
			(start -0.7874 -0.4064)
			(end -0.7874 0.4064)
			(stroke
				(width 0.1524)
				(type default)
			)
			(layer "B.SilkS")
		)
		(fp_line
			(start 0.7874 -0.4064)
			(end -0.7874 -0.4064)
			(stroke
				(width 0.1524)
				(type default)
			)
			(layer "B.SilkS")
		)
		(fp_line
			(start -0.67945 0.3048)
			(end -0.120396 0.3048)
			(stroke
				(width 0.1)
				(type default)
			)
			(layer "B.Fab")
		)
		(fp_line
			(start -0.120396 0.3048)
			(end -0.120396 0.2794)
			(stroke
				(width 0.1)
				(type default)
			)
			(layer "B.Fab")
		)
		(fp_line
			(start 0.12065 0.3048)
			(end 0.67945 0.3048)
			(stroke
				(width 0.1)
				(type default)
			)
			(layer "B.Fab")
		)
		(fp_line
			(start 0.67945 0.3048)
			(end 0.67945 -0.305054)
			(stroke
				(width 0.1)
				(type default)
			)
			(layer "B.Fab")
		)
		(fp_line
			(start -0.120396 0.2794)
			(end 0.12065 0.2794)
			(stroke
				(width 0.1)
				(type default)
			)
			(layer "B.Fab")
		)
		(fp_line
			(start 0.12065 0.2794)
			(end 0.12065 0.3048)
			(stroke
				(width 0.1)
				(type default)
			)
			(layer "B.Fab")
		)
		(fp_line
			(start -0.12065 -0.2794)
			(end -0.12065 -0.3048)
			(stroke
				(width 0.1)
				(type default)
			)
			(layer "B.Fab")
		)
		(fp_line
			(start 0.12065 -0.2794)
			(end -0.12065 -0.2794)
			(stroke
				(width 0.1)
				(type default)
			)
			(layer "B.Fab")
		)
		(fp_line
			(start -0.67945 -0.3048)
			(end -0.67945 0.3048)
			(stroke
				(width 0.1)
				(type default)
			)
			(layer "B.Fab")
		)
		(fp_line
			(start -0.12065 -0.3048)
			(end -0.67945 -0.3048)
			(stroke
				(width 0.1)
				(type default)
			)
			(layer "B.Fab")
		)
		(fp_line
			(start 0.12065 -0.305054)
			(end 0.12065 -0.2794)
			(stroke
				(width 0.1)
				(type default)
			)
			(layer "B.Fab")
		)
		(fp_line
			(start 0.67945 -0.305054)
			(end 0.12065 -0.305054)
			(stroke
				(width 0.1)
				(type default)
			)
			(layer "B.Fab")
		)
		(pad "1" smd circle
			(at 0.40005 0 90)
			(size 0 0)
			(layers "B.Cu" "B.Mask" "B.Paste")
			(net "PVDDCR_SOC_P1")
		)
		(pad "2" smd circle
			(at -0.40005 0 90)
			(size 0 0)
			(layers "B.Cu" "B.Mask" "B.Paste")
			(net "GND")
		)
	)
	(footprint ""
		(layer "B.Cu")
		(at 91.999054 -326.367902 -90)
		(property "Reference" "PC431_5"
			(at 0 0 90)
			(layer "B.SilkS")
			(hide yes)
			(effects
				(font
					(size 1.27 1.27)
				)
				(justify mirror)
			)
		)
		(property "Value" ""
			(at 0 0 90)
			(layer "B.Fab")
			(effects
				(font
					(size 1.27 1.27)
				)
				(justify mirror)
			)
		)
		(duplicate_pad_numbers_are_jumpers no)
		(fp_line
			(start -1.524 0.762)
			(end 1.524 0.762)
			(stroke
				(width 0.1524)
				(type default)
			)
			(layer "B.SilkS")
		)
		(fp_line
			(start 1.524 0.762)
			(end 1.524 -0.762)
			(stroke
				(width 0.1524)
				(type default)
			)
			(layer "B.SilkS")
		)
		(fp_line
			(start -1.524 -0.762)
			(end -1.524 0.762)
			(stroke
				(width 0.1524)
				(type default)
			)
			(layer "B.SilkS")
		)
		(fp_line
			(start 1.524 -0.762)
			(end -1.524 -0.762)
			(stroke
				(width 0.1524)
				(type default)
			)
			(layer "B.SilkS")
		)
		(fp_line
			(start -1.1049 0.724916)
			(end -1.1049 -0.724916)
			(stroke
				(width 0.1)
				(type default)
			)
			(layer "B.Fab")
		)
		(fp_line
			(start 1.1049 0.724916)
			(end -1.1049 0.724916)
			(stroke
				(width 0.1)
				(type default)
			)
			(layer "B.Fab")
		)
		(fp_line
			(start -1.1049 -0.724916)
			(end 1.1049 -0.724916)
			(stroke
				(width 0.1)
				(type default)
			)
			(layer "B.Fab")
		)
		(fp_line
			(start 1.1049 -0.724916)
			(end 1.1049 0.724916)
			(stroke
				(width 0.1)
				(type default)
			)
			(layer "B.Fab")
		)
		(pad "1" smd rect
			(at 0.889 0 270)
			(size 1.016 1.27)
			(layers "B.Cu" "B.Mask" "B.Paste")
			(net "PVDDCR_CPU1_P1")
		)
		(pad "2" smd rect
			(at -0.889 0 270)
			(size 1.016 1.27)
			(layers "B.Cu" "B.Mask" "B.Paste")
			(net "GND")
		)
	)
	(footprint ""
		(layer "B.Cu")
		(at 182.860696 -195.8594 180)
		(property "Reference" "R1708"
			(at 0 0 0)
			(layer "B.SilkS")
			(hide yes)
			(effects
				(font
					(size 1.27 1.27)
				)
				(justify mirror)
			)
		)
		(property "Value" ""
			(at 0 0 0)
			(layer "B.Fab")
			(effects
				(font
					(size 1.27 1.27)
				)
				(justify mirror)
			)
		)
		(duplicate_pad_numbers_are_jumpers no)
		(fp_line
			(start 0.7874 0.4064)
			(end 0.7874 -0.4064)
			(stroke
				(width 0.1524)
				(type default)
			)
			(layer "B.SilkS")
		)
		(fp_line
			(start 0.7874 -0.4064)
			(end -0.7874 -0.4064)
			(stroke
				(width 0.1524)
				(type default)
			)
			(layer "B.SilkS")
		)
		(fp_line
			(start -0.7874 0.4064)
			(end 0.7874 0.4064)
			(stroke
				(width 0.1524)
				(type default)
			)
			(layer "B.SilkS")
		)
		(fp_line
			(start -0.7874 -0.4064)
			(end -0.7874 0.4064)
			(stroke
				(width 0.1524)
				(type default)
			)
			(layer "B.SilkS")
		)
		(fp_line
			(start 0.67945 0.3048)
			(end 0.67945 -0.305054)
			(stroke
				(width 0.1)
				(type default)
			)
			(layer "B.Fab")
		)
		(fp_line
			(start 0.67945 -0.305054)
			(end 0.12065 -0.305054)
			(stroke
				(width 0.1)
				(type default)
			)
			(layer "B.Fab")
		)
		(fp_line
			(start 0.12065 0.3048)
			(end 0.67945 0.3048)
			(stroke
				(width 0.1)
				(type default)
			)
			(layer "B.Fab")
		)
		(fp_line
			(start 0.12065 0.2794)
			(end 0.12065 0.3048)
			(stroke
				(width 0.1)
				(type default)
			)
			(layer "B.Fab")
		)
		(fp_line
			(start 0.12065 -0.2794)
			(end -0.12065 -0.2794)
			(stroke
				(width 0.1)
				(type default)
			)
			(layer "B.Fab")
		)
		(fp_line
			(start 0.12065 -0.305054)
			(end 0.12065 -0.2794)
			(stroke
				(width 0.1)
				(type default)
			)
			(layer "B.Fab")
		)
		(fp_line
			(start -0.120396 0.3048)
			(end -0.120396 0.2794)
			(stroke
				(width 0.1)
				(type default)
			)
			(layer "B.Fab")
		)
		(fp_line
			(start -0.120396 0.2794)
			(end 0.12065 0.2794)
			(stroke
				(width 0.1)
				(type default)
			)
			(layer "B.Fab")
		)
		(fp_line
			(start -0.12065 -0.2794)
			(end -0.12065 -0.3048)
			(stroke
				(width 0.1)
				(type default)
			)
			(layer "B.Fab")
		)
		(fp_line
			(start -0.12065 -0.3048)
			(end -0.67945 -0.3048)
			(stroke
				(width 0.1)
				(type default)
			)
			(layer "B.Fab")
		)
		(fp_line
			(start -0.67945 0.3048)
			(end -0.120396 0.3048)
			(stroke
				(width 0.1)
				(type default)
			)
			(layer "B.Fab")
		)
		(fp_line
			(start -0.67945 -0.3048)
			(end -0.67945 0.3048)
			(stroke
				(width 0.1)
				(type default)
			)
			(layer "B.Fab")
		)
		(pad "1" smd circle
			(at 0.40005 0)
			(size 0 0)
			(layers "B.Cu" "B.Mask" "B.Paste")
			(net "I3C_SPD_DDRGL_CPU1_SDA")
		)
		(pad "2" smd circle
			(at -0.40005 0)
			(size 0 0)
			(layers "B.Cu" "B.Mask" "B.Paste")
			(net "I3C_SPD_DDRI_CPU1_SDA")
		)
	)
)
